(kicad_pcb
	(version 20241229)
	(generator "pcbnew")
	(generator_version "9.0")
	(general
		(thickness 1.62)
		(legacy_teardrops no)
	)
	(paper "A3")
	(title_block
		(title "COM Express 7 Baseboard")
		(date "2025-02-04")
		(rev "1.1.2")
		(company "Antmicro Ltd")
		(comment 1 "www.antmicro.com")
		(comment 9 "footprints 189-191 of 802")
	)
	(layers
		(0 "F.Cu" signal)
		(4 "In1.Cu" signal)
		(6 "In2.Cu" signal)
		(8 "In3.Cu" signal)
		(10 "In4.Cu" signal)
		(12 "In5.Cu" signal)
		(14 "In6.Cu" signal)
		(2 "B.Cu" signal)
		(9 "F.Adhes" user "F.Adhesive")
		(11 "B.Adhes" user "B.Adhesive")
		(13 "F.Paste" user)
		(15 "B.Paste" user)
		(5 "F.SilkS" user "F.Silkscreen")
		(7 "B.SilkS" user "B.Silkscreen")
		(1 "F.Mask" user)
		(3 "B.Mask" user)
		(17 "Dwgs.User" user "User.Drawings")
		(19 "Cmts.User" user "User.Comments")
		(21 "Eco1.User" user "User.Eco1")
		(23 "Eco2.User" user "User.Eco2")
		(25 "Edge.Cuts" user)
		(27 "Margin" user)
		(31 "F.CrtYd" user "F.Courtyard")
		(29 "B.CrtYd" user "B.Courtyard")
		(35 "F.Fab" user)
		(33 "B.Fab" user)
	)
	(footprint "antmicro-footprints:Spacer_Drill3.7mm_H2.5mm_9774025151R"
		(layer "F.Cu")
		(at 295.4495 157.485)
		(descr "Spacer M=3 h=2.5mm fi=5.1mm")
		(property "Reference" "H1"
			(at 0 -3.2 0)
			(layer "F.SilkS")
			(hide yes)
			(effects
				(font
					(size 0.7 0.7)
					(thickness 0.15)
				)
				(justify left bottom)
			)
		)
		(property "Value" "Spacer_Drill3.7mm_H2.5mm_9774025151R"
			(at 0 4 0)
			(layer "F.Fab")
			(effects
				(font
					(size 0.7 0.7)
					(thickness 0.15)
				)
				(justify left bottom)
			)
		)
		(property "Datasheet" "https://www.we-online.com/components/products/datasheet/9774025151R.pdf"
			(at 0 0 0)
			(layer "F.Fab")
			(hide yes)
			(effects
				(font
					(size 1.27 1.27)
					(thickness 0.15)
				)
			)
		)
		(property "Author" "Antmicro"
			(at 0 0 0)
			(layer "F.Fab")
			(hide yes)
			(effects
				(font
					(size 1 1)
					(thickness 0.15)
				)
			)
		)
		(property "License" "Apache-2.0"
			(at 0 0 0)
			(layer "F.Fab")
			(hide yes)
			(effects
				(font
					(size 1 1)
					(thickness 0.15)
				)
			)
		)
		(property "MPN" "9774025151R"
			(at 0 0 0)
			(layer "F.Fab")
			(hide yes)
			(effects
				(font
					(size 1 1)
					(thickness 0.15)
				)
			)
		)
		(property "Manufacturer" "Würth Elektronik"
			(at 0 0 0)
			(layer "F.Fab")
			(hide yes)
			(effects
				(font
					(size 1 1)
					(thickness 0.15)
				)
			)
		)
		(property "Public" "False"
			(at 0 0 0)
			(layer "F.Fab")
			(hide yes)
			(effects
				(font
					(size 1 1)
					(thickness 0.15)
				)
			)
		)
		(sheetname "M.2 key M #2")
		(sheetfile "m2keym.kicad_sch")
		(solder_paste_margin_ratio -1)
		(attr smd)
		(fp_circle
			(center 0 0)
			(end 3.05 0)
			(stroke
				(width 0.05)
				(type solid)
			)
			(fill no)
			(layer "F.CrtYd")
		)
		(fp_circle
			(center 0 0)
			(end 2.6 0)
			(stroke
				(width 0.15)
				(type solid)
			)
			(fill no)
			(layer "F.Fab")
		)
		(pad "" smd custom
			(at -1.7 -1.7)
			(size 0.62 0.62)
			(layers "F.Paste")
			(thermal_bridge_angle 90)
			(options
				(clearance outline)
				(anchor circle)
			)
			(primitives
				(gr_arc
					(start -0.250195 1.279127)
					(mid 0.285453 0.294389)
					(end 1.266786 -0.24747)
					(width 0.2)
				)
				(gr_arc
					(start -0.34334 1.279127)
					(mid 0.218448 0.232561)
					(end 1.259603 -0.339191)
					(width 0.2)
				)
				(gr_arc
					(start -0.436309 1.279127)
					(mid 0.152481 0.169693)
					(end 1.255279 -0.431435)
					(width 0.2)
				)
				(gr_arc
					(start -0.529126 1.279127)
					(mid 0.087542 0.105784)
					(end 1.253811 -0.524161)
					(width 0.2)
				)
				(gr_arc
					(start -0.621807 1.279127)
					(mid 0.0309 0.033527)
					(end 1.275473 -0.621136)
					(width 0.2)
				)
				(gr_arc
					(start -0.71437 1.279127)
					(mid -0.037758 -0.026651)
					(end 1.263664 -0.711602)
					(width 0.2)
				)
				(gr_arc
					(start -0.806826 1.279127)
					(mid -0.105837 -0.087395)
					(end 1.253435 -0.802342)
					(width 0.2)
				)
				(gr_arc
					(start -0.899187 1.279127)
					(mid -0.165236 -0.156885)
					(end 1.267475 -0.897258)
					(width 0.2)
				)
				(gr_arc
					(start -0.991463 1.279127)
					(mid -0.228522 -0.222449)
					(end 1.270645 -0.990112)
					(width 0.2)
				)
				(gr_arc
					(start -1.083663 1.279127)
					(mid -0.294507 -0.285313)
					(end 1.266278 -1.081674)
					(width 0.2)
				)
				(gr_line
					(start 1.279127 -0.250195)
					(end 1.279127 -1.083663)
					(width 0.2)
				)
				(gr_line
					(start -0.250195 1.279127)
					(end -1.083663 1.279127)
					(width 0.2)
				)
			)
			(teardrops
				(best_length_ratio 0.2)
				(max_length 1)
				(best_width_ratio 0.9)
				(max_width 2)
				(curved_edges yes)
				(filter_ratio 0.9)
				(enabled yes)
				(allow_two_segments yes)
				(prefer_zone_connections yes)
			)
		)
		(pad "" smd custom
			(at -1.7 1.7 90)
			(size 0.62 0.62)
			(layers "F.Paste")
			(thermal_bridge_angle 90)
			(options
				(clearance outline)
				(anchor circle)
			)
			(primitives
				(gr_arc
					(start -0.250195 1.279127)
					(mid 0.285453 0.294389)
					(end 1.266786 -0.24747)
					(width 0.2)
				)
				(gr_arc
					(start -0.34334 1.279127)
					(mid 0.218448 0.232561)
					(end 1.259603 -0.339191)
					(width 0.2)
				)
				(gr_arc
					(start -0.436309 1.279127)
					(mid 0.152481 0.169693)
					(end 1.255279 -0.431435)
					(width 0.2)
				)
				(gr_arc
					(start -0.529126 1.279127)
					(mid 0.087542 0.105784)
					(end 1.253811 -0.524161)
					(width 0.2)
				)
				(gr_arc
					(start -0.621807 1.279127)
					(mid 0.0309 0.033527)
					(end 1.275473 -0.621136)
					(width 0.2)
				)
				(gr_arc
					(start -0.71437 1.279127)
					(mid -0.037758 -0.026651)
					(end 1.263664 -0.711602)
					(width 0.2)
				)
				(gr_arc
					(start -0.806826 1.279127)
					(mid -0.105837 -0.087395)
					(end 1.253435 -0.802342)
					(width 0.2)
				)
				(gr_arc
					(start -0.899187 1.279127)
					(mid -0.165236 -0.156885)
					(end 1.267475 -0.897258)
					(width 0.2)
				)
				(gr_arc
					(start -0.991463 1.279127)
					(mid -0.228522 -0.222449)
					(end 1.270645 -0.990112)
					(width 0.2)
				)
				(gr_arc
					(start -1.083663 1.279127)
					(mid -0.294507 -0.285313)
					(end 1.266278 -1.081674)
					(width 0.2)
				)
				(gr_line
					(start 1.279127 -0.250195)
					(end 1.279127 -1.083663)
					(width 0.2)
				)
				(gr_line
					(start -0.250195 1.279127)
					(end -1.083663 1.279127)
					(width 0.2)
				)
			)
			(teardrops
				(best_length_ratio 0.2)
				(max_length 1)
				(best_width_ratio 0.9)
				(max_width 2)
				(curved_edges yes)
				(filter_ratio 0.9)
				(enabled yes)
				(allow_two_segments yes)
				(prefer_zone_connections yes)
			)
		)
		(pad "" smd custom
			(at 1.7 -1.7 270)
			(size 0.62 0.62)
			(layers "F.Paste")
			(thermal_bridge_angle 90)
			(options
				(clearance outline)
				(anchor circle)
			)
			(primitives
				(gr_arc
					(start -0.250195 1.279127)
					(mid 0.285453 0.294389)
					(end 1.266786 -0.24747)
					(width 0.2)
				)
				(gr_arc
					(start -0.34334 1.279127)
					(mid 0.218448 0.232561)
					(end 1.259603 -0.339191)
					(width 0.2)
				)
				(gr_arc
					(start -0.436309 1.279127)
					(mid 0.152481 0.169693)
					(end 1.255279 -0.431435)
					(width 0.2)
				)
				(gr_arc
					(start -0.529126 1.279127)
					(mid 0.087542 0.105784)
					(end 1.253811 -0.524161)
					(width 0.2)
				)
				(gr_arc
					(start -0.621807 1.279127)
					(mid 0.0309 0.033527)
					(end 1.275473 -0.621136)
					(width 0.2)
				)
				(gr_arc
					(start -0.71437 1.279127)
					(mid -0.037758 -0.026651)
					(end 1.263664 -0.711602)
					(width 0.2)
				)
				(gr_arc
					(start -0.806826 1.279127)
					(mid -0.105837 -0.087395)
					(end 1.253435 -0.802342)
					(width 0.2)
				)
				(gr_arc
					(start -0.899187 1.279127)
					(mid -0.165236 -0.156885)
					(end 1.267475 -0.897258)
					(width 0.2)
				)
				(gr_arc
					(start -0.991463 1.279127)
					(mid -0.228522 -0.222449)
					(end 1.270645 -0.990112)
					(width 0.2)
				)
				(gr_arc
					(start -1.083663 1.279127)
					(mid -0.294507 -0.285313)
					(end 1.266278 -1.081674)
					(width 0.2)
				)
				(gr_line
					(start 1.279127 -0.250195)
					(end 1.279127 -1.083663)
					(width 0.2)
				)
				(gr_line
					(start -0.250195 1.279127)
					(end -1.083663 1.279127)
					(width 0.2)
				)
			)
			(teardrops
				(best_length_ratio 0.2)
				(max_length 1)
				(best_width_ratio 0.9)
				(max_width 2)
				(curved_edges yes)
				(filter_ratio 0.9)
				(enabled yes)
				(allow_two_segments yes)
				(prefer_zone_connections yes)
			)
		)
		(pad "" smd custom
			(at 1.7 1.7 180)
			(size 0.62 0.62)
			(layers "F.Paste")
			(thermal_bridge_angle 90)
			(options
				(clearance outline)
				(anchor circle)
			)
			(primitives
				(gr_arc
					(start -0.250195 1.279127)
					(mid 0.285453 0.294389)
					(end 1.266786 -0.24747)
					(width 0.2)
				)
				(gr_arc
					(start -0.34334 1.279127)
					(mid 0.218448 0.232561)
					(end 1.259603 -0.339191)
					(width 0.2)
				)
				(gr_arc
					(start -0.436309 1.279127)
					(mid 0.152481 0.169693)
					(end 1.255279 -0.431435)
					(width 0.2)
				)
				(gr_arc
					(start -0.529126 1.279127)
					(mid 0.087542 0.105784)
					(end 1.253811 -0.524161)
					(width 0.2)
				)
				(gr_arc
					(start -0.621807 1.279127)
					(mid 0.0309 0.033527)
					(end 1.275473 -0.621136)
					(width 0.2)
				)
				(gr_arc
					(start -0.71437 1.279127)
					(mid -0.037758 -0.026651)
					(end 1.263664 -0.711602)
					(width 0.2)
				)
				(gr_arc
					(start -0.806826 1.279127)
					(mid -0.105837 -0.087395)
					(end 1.253435 -0.802342)
					(width 0.2)
				)
				(gr_arc
					(start -0.899187 1.279127)
					(mid -0.165236 -0.156885)
					(end 1.267475 -0.897258)
					(width 0.2)
				)
				(gr_arc
					(start -0.991463 1.279127)
					(mid -0.228522 -0.222449)
					(end 1.270645 -0.990112)
					(width 0.2)
				)
				(gr_arc
					(start -1.083663 1.279127)
					(mid -0.294507 -0.285313)
					(end 1.266278 -1.081674)
					(width 0.2)
				)
				(gr_line
					(start 1.279127 -0.250195)
					(end 1.279127 -1.083663)
					(width 0.2)
				)
				(gr_line
					(start -0.250195 1.279127)
					(end -1.083663 1.279127)
					(width 0.2)
				)
			)
			(teardrops
				(best_length_ratio 0.2)
				(max_length 1)
				(best_width_ratio 0.9)
				(max_width 2)
				(curved_edges yes)
				(filter_ratio 0.9)
				(enabled yes)
				(allow_two_segments yes)
				(prefer_zone_connections yes)
			)
		)
		(pad "1" thru_hole circle
			(at 0 0)
			(size 6 6)
			(drill 3.7)
			(layers "*.Cu" "*.Mask")
			(remove_unused_layers no)
			(net 1 "GND")
			(pintype "passive")
			(teardrops
				(best_length_ratio 0.4)
				(max_length 1)
				(best_width_ratio 0.9)
				(max_width 2)
				(curved_edges yes)
				(filter_ratio 0.9)
				(enabled yes)
				(allow_two_segments yes)
				(prefer_zone_connections yes)
			)
		)
	)
	(footprint "antmicro-footprints:R_0201"
		(layer "F.Cu")
		(at 147.33 147.935 -90)
		(descr "Resistor SMD 0201")
		(tags "resistor SMD 0201")
		(property "Reference" "R279"
			(at 3.62 -0.57 90)
			(layer "F.SilkS")
			(effects
				(font
					(size 0.7 0.7)
					(thickness 0.15)
				)
				(justify right bottom)
			)
		)
		(property "Value" "R_0R_0201"
			(at 0 1.25 90)
			(layer "F.Fab")
			(effects
				(font
					(size 0.7 0.7)
					(thickness 0.15)
				)
				(justify right bottom)
			)
		)
		(property "Datasheet" "https://www.bourns.com/docs/product-datasheets/cr.pdf"
			(at 0 0 270)
			(layer "F.Fab")
			(hide yes)
			(effects
				(font
					(size 1.27 1.27)
					(thickness 0.15)
				)
			)
		)
		(property "Author" "Antmicro"
			(at -0.605 295.265 0)
			(layer "F.Fab")
			(hide yes)
			(effects
				(font
					(size 1 1)
					(thickness 0.15)
				)
			)
		)
		(property "License" "Apache-2.0"
			(at -0.605 295.265 0)
			(layer "F.Fab")
			(hide yes)
			(effects
				(font
					(size 1 1)
					(thickness 0.15)
				)
			)
		)
		(property "MPN" "CR0201-FX-0R00GLF"
			(at -0.605 295.265 0)
			(layer "F.Fab")
			(hide yes)
			(effects
				(font
					(size 1 1)
					(thickness 0.15)
				)
			)
		)
		(property "Manufacturer" "Bourns"
			(at -0.605 295.265 0)
			(layer "F.Fab")
			(hide yes)
			(effects
				(font
					(size 1 1)
					(thickness 0.15)
				)
			)
		)
		(property "Tolerance" "1%"
			(at -0.605 295.265 0)
			(layer "F.Fab")
			(hide yes)
			(effects
				(font
					(size 1 1)
					(thickness 0.15)
				)
			)
		)
		(property "Val" "0R"
			(at -0.605 295.265 0)
			(layer "F.Fab")
			(hide yes)
			(effects
				(font
					(size 1 1)
					(thickness 0.15)
				)
			)
		)
		(sheetname "KR to SFI #1")
		(sheetfile "kr_sfi.kicad_sch")
		(attr smd dnp)
		(fp_rect
			(start -0.7 -0.35)
			(end 0.7 0.35)
			(stroke
				(width 0.05)
				(type default)
			)
			(fill no)
			(layer "F.CrtYd")
		)
		(fp_rect
			(start -0.3 -0.15)
			(end 0.298 0.148)
			(stroke
				(width 0.15)
				(type solid)
			)
			(fill no)
			(layer "F.Fab")
		)
		(pad "" smd roundrect
			(at -0.346 0 270)
			(size 0.318 0.36)
			(layers "F.Paste")
			(roundrect_rratio 0.25)
			(teardrops
				(best_length_ratio 0.2)
				(max_length 1)
				(best_width_ratio 0.9)
				(max_width 2)
				(curved_edges yes)
				(filter_ratio 0.9)
				(enabled yes)
				(allow_two_segments yes)
				(prefer_zone_connections yes)
			)
		)
		(pad "" smd roundrect
			(at 0.344 0 270)
			(size 0.318 0.36)
			(layers "F.Paste")
			(roundrect_rratio 0.25)
			(teardrops
				(best_length_ratio 0.2)
				(max_length 1)
				(best_width_ratio 0.9)
				(max_width 2)
				(curved_edges yes)
				(filter_ratio 0.9)
				(enabled yes)
				(allow_two_segments yes)
				(prefer_zone_connections yes)
			)
		)
		(pad "1" smd roundrect
			(at -0.32 0 270)
			(size 0.46 0.4)
			(layers "F.Cu" "F.Mask")
			(roundrect_rratio 0.25)
			(net 172 "/2xSFP+/SFI0.TX+")
			(pintype "passive")
			(teardrops
				(best_length_ratio 0.2)
				(max_length 1)
				(best_width_ratio 0.9)
				(max_width 2)
				(curved_edges yes)
				(filter_ratio 0.9)
				(enabled yes)
				(allow_two_segments yes)
				(prefer_zone_connections yes)
			)
		)
		(pad "2" smd roundrect
			(at 0.32 0 270)
			(size 0.46 0.4)
			(layers "F.Cu" "F.Mask")
			(roundrect_rratio 0.25)
			(net 954 "/2xSFP+/KR to SFI #1/BYP_TX+")
			(pintype "passive")
			(teardrops
				(best_length_ratio 0.2)
				(max_length 1)
				(best_width_ratio 0.9)
				(max_width 2)
				(curved_edges yes)
				(filter_ratio 0.9)
				(enabled yes)
				(allow_two_segments yes)
				(prefer_zone_connections yes)
			)
		)
	)
	(footprint "antmicro-footprints:R_0402_1005Metric"
		(layer "F.Cu")
		(at 111.206998 76.326)
		(descr "Resistor SMD 0402")
		(tags "resistor SMD 0402")
		(property "Reference" "R70"
			(at -1.056998 1.334 0)
			(layer "F.SilkS")
			(effects
				(font
					(size 0.7 0.7)
					(thickness 0.15)
				)
				(justify left bottom)
			)
		)
		(property "Value" "R_27R_0402"
			(at -1.011843 1.772047 0)
			(layer "F.Fab")
			(effects
				(font
					(size 0.7 0.7)
					(thickness 0.15)
				)
				(justify left bottom)
			)
		)
		(property "Datasheet" "https://www.bourns.com/docs/product-datasheets/cr.pdf"
			(at 0 0 0)
			(layer "F.Fab")
			(hide yes)
			(effects
				(font
					(size 1.27 1.27)
					(thickness 0.15)
				)
			)
		)
		(property "Author" "Antmicro"
			(at 0 0 0)
			(layer "F.Fab")
			(hide yes)
			(effects
				(font
					(size 1 1)
					(thickness 0.15)
				)
			)
		)
		(property "License" "Apache-2.0"
			(at 0 0 0)
			(layer "F.Fab")
			(hide yes)
			(effects
				(font
					(size 1 1)
					(thickness 0.15)
				)
			)
		)
		(property "MPN" "CR0402-FX-27R0GLF"
			(at 0 0 0)
			(layer "F.Fab")
			(hide yes)
			(effects
				(font
					(size 1 1)
					(thickness 0.15)
				)
			)
		)
		(property "Manufacturer" "Bourns"
			(at 0 0 0)
			(layer "F.Fab")
			(hide yes)
			(effects
				(font
					(size 1 1)
					(thickness 0.15)
				)
			)
		)
		(property "Public" "False"
			(at 0 0 0)
			(layer "F.Fab")
			(hide yes)
			(effects
				(font
					(size 1 1)
					(thickness 0.15)
				)
			)
		)
		(property "Tolerance" "1%"
			(at 0 0 0)
			(layer "F.Fab")
			(hide yes)
			(effects
				(font
					(size 1 1)
					(thickness 0.15)
				)
			)
		)
		(property "Val" "27R"
			(at 0 0 0)
			(layer "F.Fab")
			(hide yes)
			(effects
				(font
					(size 1 1)
					(thickness 0.15)
				)
			)
		)
		(sheetname "USB-C console")
		(sheetfile "usb-c_console.kicad_sch")
		(attr smd)
		(fp_rect
			(start -0.925 -0.47)
			(end 0.925 0.47)
			(stroke
				(width 0.05)
				(type default)
			)
			(fill no)
			(layer "F.CrtYd")
		)
		(fp_rect
			(start -0.5 -0.25)
			(end 0.5 0.25)
			(stroke
				(width 0.15)
				(type solid)
			)
			(fill no)
			(layer "F.Fab")
		)
		(pad "1" smd roundrect
			(at -0.48 0)
			(size 0.59 0.64)
			(layers "F.Cu" "F.Mask" "F.Paste")
			(roundrect_rratio 0.25)
			(net 56 "/USB-C console/USB_D-")
			(pintype "passive")
			(teardrops
				(best_length_ratio 0.2)
				(max_length 1)
				(best_width_ratio 0.9)
				(max_width 2)
				(curved_edges yes)
				(filter_ratio 0.9)
				(enabled yes)
				(allow_two_segments yes)
				(prefer_zone_connections yes)
			)
		)
		(pad "2" smd roundrect
			(at 0.48 0)
			(size 0.59 0.64)
			(layers "F.Cu" "F.Mask" "F.Paste")
			(roundrect_rratio 0.25)
			(net 569 "/USB-C console/FTDI_D-")
			(pintype "passive")
			(teardrops
				(best_length_ratio 0.2)
				(max_length 1)
				(best_width_ratio 0.9)
				(max_width 2)
				(curved_edges yes)
				(filter_ratio 0.9)
				(enabled yes)
				(allow_two_segments yes)
				(prefer_zone_connections yes)
			)
		)
	)
)
